(kicad_pcb
	(version 20260206)
	(generator "pcbnew")
	(generator_version "10.0")
	(general
		(thickness 1.6)
		(legacy_teardrops no)
	)
	(paper "A4")
	(title_block
		(title "12092022_DA0F0TFB6D0_F0T_FAN_BOARD_MP5048_D_brd_v02_OCP.brd")
		(comment 1 "Grand Teton / footprints 548-553 of 924")
	)
	(layers
		(0 "F.Cu" signal "TOP")
		(4 "In1.Cu" signal "GND")
		(6 "In2.Cu" signal "IN1")
		(8 "In3.Cu" signal "IN2")
		(10 "In4.Cu" signal "GND1")
		(2 "B.Cu" signal "BOTTOM")
		(9 "F.Adhes" user "F.Adhesive")
		(11 "B.Adhes" user "B.Adhesive")
		(13 "F.Paste" user "Package Geometry/Pastemask Top")
		(15 "B.Paste" user "Package Geometry/Pastemask Bottom")
		(5 "F.SilkS" user "Ref Des/Silkscreen Top")
		(7 "B.SilkS" user "Ref Des/Silkscreen Bottom")
		(1 "F.Mask" user "Board Geometry/Soldermask Top")
		(3 "B.Mask" user "Board Geometry/Soldermask Bottom")
		(17 "Dwgs.User" user "User.Drawings")
		(19 "Cmts.User" user "User.Comments")
		(21 "Eco1.User" user "User.Eco1")
		(23 "Eco2.User" user "User.Eco2")
		(25 "Edge.Cuts" user "Board Geometry/Outline")
		(27 "Margin" user)
		(31 "F.CrtYd" user "Package Geometry/Place Bound Top")
		(29 "B.CrtYd" user "Package Geometry/Place Bound Bottom")
		(35 "F.Fab" user "Ref Des/Assembly Top")
		(33 "B.Fab" user "Ref Des/Assembly Bottom")
	)
	(footprint ""
		(layer "F.Cu")
		(at 21.717 -303.53 90)
		(property "Reference" "C100"
			(at 0 0 90)
			(layer "F.SilkS")
			(hide yes)
			(effects
				(font
					(size 1.27 1.27)
				)
			)
		)
		(property "Value" ""
			(at 0 0 90)
			(layer "F.Fab")
			(effects
				(font
					(size 1.27 1.27)
				)
			)
		)
		(duplicate_pad_numbers_are_jumpers no)
		(fp_line
			(start 0.7874 -0.4064)
			(end 0.7874 0.4064)
			(stroke
				(width 0.1524)
				(type default)
			)
			(layer "F.SilkS")
		)
		(fp_line
			(start -0.7874 -0.4064)
			(end 0.7874 -0.4064)
			(stroke
				(width 0.1524)
				(type default)
			)
			(layer "F.SilkS")
		)
		(fp_line
			(start 0.7874 0.4064)
			(end -0.7874 0.4064)
			(stroke
				(width 0.1524)
				(type default)
			)
			(layer "F.SilkS")
		)
		(fp_line
			(start -0.7874 0.4064)
			(end -0.7874 -0.4064)
			(stroke
				(width 0.1524)
				(type default)
			)
			(layer "F.SilkS")
		)
		(fp_line
			(start -0.12065 -0.305054)
			(end -0.12065 -0.2794)
			(stroke
				(width 0.1)
				(type default)
			)
			(layer "F.Fab")
		)
		(fp_line
			(start -0.67945 -0.305054)
			(end -0.12065 -0.305054)
			(stroke
				(width 0.1)
				(type default)
			)
			(layer "F.Fab")
		)
		(fp_line
			(start 0.67945 -0.3048)
			(end 0.67945 0.3048)
			(stroke
				(width 0.1)
				(type default)
			)
			(layer "F.Fab")
		)
		(fp_line
			(start 0.12065 -0.3048)
			(end 0.67945 -0.3048)
			(stroke
				(width 0.1)
				(type default)
			)
			(layer "F.Fab")
		)
		(fp_line
			(start 0.12065 -0.2794)
			(end 0.12065 -0.3048)
			(stroke
				(width 0.1)
				(type default)
			)
			(layer "F.Fab")
		)
		(fp_line
			(start -0.12065 -0.2794)
			(end 0.12065 -0.2794)
			(stroke
				(width 0.1)
				(type default)
			)
			(layer "F.Fab")
		)
		(fp_line
			(start 0.120396 0.2794)
			(end -0.12065 0.2794)
			(stroke
				(width 0.1)
				(type default)
			)
			(layer "F.Fab")
		)
		(fp_line
			(start -0.12065 0.2794)
			(end -0.12065 0.3048)
			(stroke
				(width 0.1)
				(type default)
			)
			(layer "F.Fab")
		)
		(fp_line
			(start 0.67945 0.3048)
			(end 0.120396 0.3048)
			(stroke
				(width 0.1)
				(type default)
			)
			(layer "F.Fab")
		)
		(fp_line
			(start 0.120396 0.3048)
			(end 0.120396 0.2794)
			(stroke
				(width 0.1)
				(type default)
			)
			(layer "F.Fab")
		)
		(fp_line
			(start -0.12065 0.3048)
			(end -0.67945 0.3048)
			(stroke
				(width 0.1)
				(type default)
			)
			(layer "F.Fab")
		)
		(fp_line
			(start -0.67945 0.3048)
			(end -0.67945 -0.305054)
			(stroke
				(width 0.1)
				(type default)
			)
			(layer "F.Fab")
		)
		(pad "1" smd circle
			(at -0.40005 0 90)
			(size 0 0)
			(layers "F.Cu" "F.Mask" "F.Paste")
			(net "P3V3_AUX")
		)
		(pad "2" smd circle
			(at 0.40005 0 90)
			(size 0 0)
			(layers "F.Cu" "F.Mask" "F.Paste")
			(net "GND")
		)
	)
	(footprint ""
		(layer "F.Cu")
		(at 45.085 -124.079 -90)
		(property "Reference" "R5694"
			(at 0 0 270)
			(layer "F.SilkS")
			(hide yes)
			(effects
				(font
					(size 1.27 1.27)
				)
			)
		)
		(property "Value" ""
			(at 0 0 270)
			(layer "F.Fab")
			(effects
				(font
					(size 1.27 1.27)
				)
			)
		)
		(duplicate_pad_numbers_are_jumpers no)
		(fp_line
			(start -0.7874 0.4064)
			(end -0.7874 -0.4064)
			(stroke
				(width 0.1524)
				(type default)
			)
			(layer "F.SilkS")
		)
		(fp_line
			(start 0.7874 0.4064)
			(end -0.7874 0.4064)
			(stroke
				(width 0.1524)
				(type default)
			)
			(layer "F.SilkS")
		)
		(fp_line
			(start -0.7874 -0.4064)
			(end 0.7874 -0.4064)
			(stroke
				(width 0.1524)
				(type default)
			)
			(layer "F.SilkS")
		)
		(fp_line
			(start 0.7874 -0.4064)
			(end 0.7874 0.4064)
			(stroke
				(width 0.1524)
				(type default)
			)
			(layer "F.SilkS")
		)
		(fp_line
			(start -0.67945 0.3048)
			(end -0.67945 -0.305054)
			(stroke
				(width 0.1)
				(type default)
			)
			(layer "F.Fab")
		)
		(fp_line
			(start -0.12065 0.3048)
			(end -0.67945 0.3048)
			(stroke
				(width 0.1)
				(type default)
			)
			(layer "F.Fab")
		)
		(fp_line
			(start 0.120396 0.3048)
			(end 0.120396 0.2794)
			(stroke
				(width 0.1)
				(type default)
			)
			(layer "F.Fab")
		)
		(fp_line
			(start 0.67945 0.3048)
			(end 0.120396 0.3048)
			(stroke
				(width 0.1)
				(type default)
			)
			(layer "F.Fab")
		)
		(fp_line
			(start -0.12065 0.2794)
			(end -0.12065 0.3048)
			(stroke
				(width 0.1)
				(type default)
			)
			(layer "F.Fab")
		)
		(fp_line
			(start 0.120396 0.2794)
			(end -0.12065 0.2794)
			(stroke
				(width 0.1)
				(type default)
			)
			(layer "F.Fab")
		)
		(fp_line
			(start -0.12065 -0.2794)
			(end 0.12065 -0.2794)
			(stroke
				(width 0.1)
				(type default)
			)
			(layer "F.Fab")
		)
		(fp_line
			(start 0.12065 -0.2794)
			(end 0.12065 -0.3048)
			(stroke
				(width 0.1)
				(type default)
			)
			(layer "F.Fab")
		)
		(fp_line
			(start 0.12065 -0.3048)
			(end 0.67945 -0.3048)
			(stroke
				(width 0.1)
				(type default)
			)
			(layer "F.Fab")
		)
		(fp_line
			(start 0.67945 -0.3048)
			(end 0.67945 0.3048)
			(stroke
				(width 0.1)
				(type default)
			)
			(layer "F.Fab")
		)
		(fp_line
			(start -0.67945 -0.305054)
			(end -0.12065 -0.305054)
			(stroke
				(width 0.1)
				(type default)
			)
			(layer "F.Fab")
		)
		(fp_line
			(start -0.12065 -0.305054)
			(end -0.12065 -0.2794)
			(stroke
				(width 0.1)
				(type default)
			)
			(layer "F.Fab")
		)
		(pad "1" smd rect
			(at -0.40005 0 90)
			(size 0.4572 0.508)
			(layers "F.Cu" "F.Mask" "F.Paste")
			(net "P12V_LED_R_FAN2")
		)
		(pad "2" smd rect
			(at 0.40005 0 90)
			(size 0.4572 0.508)
			(layers "F.Cu" "F.Mask" "F.Paste")
			(net "P12V_LED_R1_FAN2")
		)
	)
	(footprint ""
		(layer "F.Cu")
		(at 24.638 -185.674 180)
		(property "Reference" "C2085"
			(at 0 0 180)
			(layer "F.SilkS")
			(hide yes)
			(effects
				(font
					(size 1.27 1.27)
				)
			)
		)
		(property "Value" ""
			(at 0 0 180)
			(layer "F.Fab")
			(effects
				(font
					(size 1.27 1.27)
				)
			)
		)
		(duplicate_pad_numbers_are_jumpers no)
		(fp_line
			(start 0.7874 0.4064)
			(end -0.7874 0.4064)
			(stroke
				(width 0.1524)
				(type default)
			)
			(layer "F.SilkS")
		)
		(fp_line
			(start 0.7874 -0.4064)
			(end 0.7874 0.4064)
			(stroke
				(width 0.1524)
				(type default)
			)
			(layer "F.SilkS")
		)
		(fp_line
			(start -0.7874 0.4064)
			(end -0.7874 -0.4064)
			(stroke
				(width 0.1524)
				(type default)
			)
			(layer "F.SilkS")
		)
		(fp_line
			(start -0.7874 -0.4064)
			(end 0.7874 -0.4064)
			(stroke
				(width 0.1524)
				(type default)
			)
			(layer "F.SilkS")
		)
		(fp_line
			(start 0.67945 0.3048)
			(end 0.120396 0.3048)
			(stroke
				(width 0.1)
				(type default)
			)
			(layer "F.Fab")
		)
		(fp_line
			(start 0.67945 -0.3048)
			(end 0.67945 0.3048)
			(stroke
				(width 0.1)
				(type default)
			)
			(layer "F.Fab")
		)
		(fp_line
			(start 0.12065 -0.2794)
			(end 0.12065 -0.3048)
			(stroke
				(width 0.1)
				(type default)
			)
			(layer "F.Fab")
		)
		(fp_line
			(start 0.12065 -0.3048)
			(end 0.67945 -0.3048)
			(stroke
				(width 0.1)
				(type default)
			)
			(layer "F.Fab")
		)
		(fp_line
			(start 0.120396 0.3048)
			(end 0.120396 0.2794)
			(stroke
				(width 0.1)
				(type default)
			)
			(layer "F.Fab")
		)
		(fp_line
			(start 0.120396 0.2794)
			(end -0.12065 0.2794)
			(stroke
				(width 0.1)
				(type default)
			)
			(layer "F.Fab")
		)
		(fp_line
			(start -0.12065 0.3048)
			(end -0.67945 0.3048)
			(stroke
				(width 0.1)
				(type default)
			)
			(layer "F.Fab")
		)
		(fp_line
			(start -0.12065 0.2794)
			(end -0.12065 0.3048)
			(stroke
				(width 0.1)
				(type default)
			)
			(layer "F.Fab")
		)
		(fp_line
			(start -0.12065 -0.2794)
			(end 0.12065 -0.2794)
			(stroke
				(width 0.1)
				(type default)
			)
			(layer "F.Fab")
		)
		(fp_line
			(start -0.12065 -0.305054)
			(end -0.12065 -0.2794)
			(stroke
				(width 0.1)
				(type default)
			)
			(layer "F.Fab")
		)
		(fp_line
			(start -0.67945 0.3048)
			(end -0.67945 -0.305054)
			(stroke
				(width 0.1)
				(type default)
			)
			(layer "F.Fab")
		)
		(fp_line
			(start -0.67945 -0.305054)
			(end -0.12065 -0.305054)
			(stroke
				(width 0.1)
				(type default)
			)
			(layer "F.Fab")
		)
		(pad "1" smd circle
			(at -0.40005 0 180)
			(size 0 0)
			(layers "F.Cu" "F.Mask" "F.Paste")
			(net "P52V_FAN_6_BUFF_EN_R")
		)
		(pad "2" smd circle
			(at 0.40005 0 180)
			(size 0 0)
			(layers "F.Cu" "F.Mask" "F.Paste")
			(net "GND")
		)
	)
	(footprint ""
		(layer "F.Cu")
		(at 33.02 -300.609 180)
		(property "Reference" "C2022"
			(at 0 0 180)
			(layer "F.SilkS")
			(hide yes)
			(effects
				(font
					(size 1.27 1.27)
				)
			)
		)
		(property "Value" ""
			(at 0 0 180)
			(layer "F.Fab")
			(effects
				(font
					(size 1.27 1.27)
				)
			)
		)
		(duplicate_pad_numbers_are_jumpers no)
		(fp_line
			(start 0.7874 0.4064)
			(end -0.7874 0.4064)
			(stroke
				(width 0.1524)
				(type default)
			)
			(layer "F.SilkS")
		)
		(fp_line
			(start 0.7874 -0.4064)
			(end 0.7874 0.4064)
			(stroke
				(width 0.1524)
				(type default)
			)
			(layer "F.SilkS")
		)
		(fp_line
			(start -0.7874 0.4064)
			(end -0.7874 -0.4064)
			(stroke
				(width 0.1524)
				(type default)
			)
			(layer "F.SilkS")
		)
		(fp_line
			(start -0.7874 -0.4064)
			(end 0.7874 -0.4064)
			(stroke
				(width 0.1524)
				(type default)
			)
			(layer "F.SilkS")
		)
		(fp_line
			(start 0.67945 0.3048)
			(end 0.120396 0.3048)
			(stroke
				(width 0.1)
				(type default)
			)
			(layer "F.Fab")
		)
		(fp_line
			(start 0.67945 -0.3048)
			(end 0.67945 0.3048)
			(stroke
				(width 0.1)
				(type default)
			)
			(layer "F.Fab")
		)
		(fp_line
			(start 0.12065 -0.2794)
			(end 0.12065 -0.3048)
			(stroke
				(width 0.1)
				(type default)
			)
			(layer "F.Fab")
		)
		(fp_line
			(start 0.12065 -0.3048)
			(end 0.67945 -0.3048)
			(stroke
				(width 0.1)
				(type default)
			)
			(layer "F.Fab")
		)
		(fp_line
			(start 0.120396 0.3048)
			(end 0.120396 0.2794)
			(stroke
				(width 0.1)
				(type default)
			)
			(layer "F.Fab")
		)
		(fp_line
			(start 0.120396 0.2794)
			(end -0.12065 0.2794)
			(stroke
				(width 0.1)
				(type default)
			)
			(layer "F.Fab")
		)
		(fp_line
			(start -0.12065 0.3048)
			(end -0.67945 0.3048)
			(stroke
				(width 0.1)
				(type default)
			)
			(layer "F.Fab")
		)
		(fp_line
			(start -0.12065 0.2794)
			(end -0.12065 0.3048)
			(stroke
				(width 0.1)
				(type default)
			)
			(layer "F.Fab")
		)
		(fp_line
			(start -0.12065 -0.2794)
			(end 0.12065 -0.2794)
			(stroke
				(width 0.1)
				(type default)
			)
			(layer "F.Fab")
		)
		(fp_line
			(start -0.12065 -0.305054)
			(end -0.12065 -0.2794)
			(stroke
				(width 0.1)
				(type default)
			)
			(layer "F.Fab")
		)
		(fp_line
			(start -0.67945 0.3048)
			(end -0.67945 -0.305054)
			(stroke
				(width 0.1)
				(type default)
			)
			(layer "F.Fab")
		)
		(fp_line
			(start -0.67945 -0.305054)
			(end -0.12065 -0.305054)
			(stroke
				(width 0.1)
				(type default)
			)
			(layer "F.Fab")
		)
		(pad "1" smd circle
			(at -0.40005 0 180)
			(size 0 0)
			(layers "F.Cu" "F.Mask" "F.Paste")
			(net "FAN_0_TACH_IL_R")
		)
		(pad "2" smd circle
			(at 0.40005 0 180)
			(size 0 0)
			(layers "F.Cu" "F.Mask" "F.Paste")
			(net "GND")
		)
	)
	(footprint ""
		(layer "F.Cu")
		(at 37.719 -98.806 90)
		(property "Reference" "R5656"
			(at 0 0 90)
			(layer "F.SilkS")
			(hide yes)
			(effects
				(font
					(size 1.27 1.27)
				)
			)
		)
		(property "Value" ""
			(at 0 0 90)
			(layer "F.Fab")
			(effects
				(font
					(size 1.27 1.27)
				)
			)
		)
		(duplicate_pad_numbers_are_jumpers no)
		(fp_line
			(start 0.7874 -0.4064)
			(end 0.7874 0.4064)
			(stroke
				(width 0.1524)
				(type default)
			)
			(layer "F.SilkS")
		)
		(fp_line
			(start -0.7874 -0.4064)
			(end 0.7874 -0.4064)
			(stroke
				(width 0.1524)
				(type default)
			)
			(layer "F.SilkS")
		)
		(fp_line
			(start 0.7874 0.4064)
			(end -0.7874 0.4064)
			(stroke
				(width 0.1524)
				(type default)
			)
			(layer "F.SilkS")
		)
		(fp_line
			(start -0.7874 0.4064)
			(end -0.7874 -0.4064)
			(stroke
				(width 0.1524)
				(type default)
			)
			(layer "F.SilkS")
		)
		(fp_line
			(start -0.12065 -0.305054)
			(end -0.12065 -0.2794)
			(stroke
				(width 0.1)
				(type default)
			)
			(layer "F.Fab")
		)
		(fp_line
			(start -0.67945 -0.305054)
			(end -0.12065 -0.305054)
			(stroke
				(width 0.1)
				(type default)
			)
			(layer "F.Fab")
		)
		(fp_line
			(start 0.67945 -0.3048)
			(end 0.67945 0.3048)
			(stroke
				(width 0.1)
				(type default)
			)
			(layer "F.Fab")
		)
		(fp_line
			(start 0.12065 -0.3048)
			(end 0.67945 -0.3048)
			(stroke
				(width 0.1)
				(type default)
			)
			(layer "F.Fab")
		)
		(fp_line
			(start 0.12065 -0.2794)
			(end 0.12065 -0.3048)
			(stroke
				(width 0.1)
				(type default)
			)
			(layer "F.Fab")
		)
		(fp_line
			(start -0.12065 -0.2794)
			(end 0.12065 -0.2794)
			(stroke
				(width 0.1)
				(type default)
			)
			(layer "F.Fab")
		)
		(fp_line
			(start 0.120396 0.2794)
			(end -0.12065 0.2794)
			(stroke
				(width 0.1)
				(type default)
			)
			(layer "F.Fab")
		)
		(fp_line
			(start -0.12065 0.2794)
			(end -0.12065 0.3048)
			(stroke
				(width 0.1)
				(type default)
			)
			(layer "F.Fab")
		)
		(fp_line
			(start 0.67945 0.3048)
			(end 0.120396 0.3048)
			(stroke
				(width 0.1)
				(type default)
			)
			(layer "F.Fab")
		)
		(fp_line
			(start 0.120396 0.3048)
			(end 0.120396 0.2794)
			(stroke
				(width 0.1)
				(type default)
			)
			(layer "F.Fab")
		)
		(fp_line
			(start -0.12065 0.3048)
			(end -0.67945 0.3048)
			(stroke
				(width 0.1)
				(type default)
			)
			(layer "F.Fab")
		)
		(fp_line
			(start -0.67945 0.3048)
			(end -0.67945 -0.305054)
			(stroke
				(width 0.1)
				(type default)
			)
			(layer "F.Fab")
		)
		(pad "1" smd circle
			(at -0.40005 0 90)
			(size 0 0)
			(layers "F.Cu" "F.Mask" "F.Paste")
			(net "FAN_2_PRESENT")
		)
		(pad "2" smd circle
			(at 0.40005 0 90)
			(size 0 0)
			(layers "F.Cu" "F.Mask" "F.Paste")
			(net "GND")
		)
	)
	(footprint ""
		(layer "F.Cu")
		(at 14.87805 -122.047)
		(property "Reference" "R5609"
			(at 0 0 0)
			(layer "F.SilkS")
			(hide yes)
			(effects
				(font
					(size 1.27 1.27)
				)
			)
		)
		(property "Value" ""
			(at 0 0 0)
			(layer "F.Fab")
			(effects
				(font
					(size 1.27 1.27)
				)
			)
		)
		(duplicate_pad_numbers_are_jumpers no)
		(fp_line
			(start -0.7874 -0.4064)
			(end 0.7874 -0.4064)
			(stroke
				(width 0.1524)
				(type default)
			)
			(layer "F.SilkS")
		)
		(fp_line
			(start -0.7874 0.4064)
			(end -0.7874 -0.4064)
			(stroke
				(width 0.1524)
				(type default)
			)
			(layer "F.SilkS")
		)
		(fp_line
			(start 0.7874 -0.4064)
			(end 0.7874 0.4064)
			(stroke
				(width 0.1524)
				(type default)
			)
			(layer "F.SilkS")
		)
		(fp_line
			(start 0.7874 0.4064)
			(end -0.7874 0.4064)
			(stroke
				(width 0.1524)
				(type default)
			)
			(layer "F.SilkS")
		)
		(fp_line
			(start -0.67945 -0.305054)
			(end -0.12065 -0.305054)
			(stroke
				(width 0.1)
				(type default)
			)
			(layer "F.Fab")
		)
		(fp_line
			(start -0.67945 0.3048)
			(end -0.67945 -0.305054)
			(stroke
				(width 0.1)
				(type default)
			)
			(layer "F.Fab")
		)
		(fp_line
			(start -0.12065 -0.305054)
			(end -0.12065 -0.2794)
			(stroke
				(width 0.1)
				(type default)
			)
			(layer "F.Fab")
		)
		(fp_line
			(start -0.12065 -0.2794)
			(end 0.12065 -0.2794)
			(stroke
				(width 0.1)
				(type default)
			)
			(layer "F.Fab")
		)
		(fp_line
			(start -0.12065 0.2794)
			(end -0.12065 0.3048)
			(stroke
				(width 0.1)
				(type default)
			)
			(layer "F.Fab")
		)
		(fp_line
			(start -0.12065 0.3048)
			(end -0.67945 0.3048)
			(stroke
				(width 0.1)
				(type default)
			)
			(layer "F.Fab")
		)
		(fp_line
			(start 0.120396 0.2794)
			(end -0.12065 0.2794)
			(stroke
				(width 0.1)
				(type default)
			)
			(layer "F.Fab")
		)
		(fp_line
			(start 0.120396 0.3048)
			(end 0.120396 0.2794)
			(stroke
				(width 0.1)
				(type default)
			)
			(layer "F.Fab")
		)
		(fp_line
			(start 0.12065 -0.3048)
			(end 0.67945 -0.3048)
			(stroke
				(width 0.1)
				(type default)
			)
			(layer "F.Fab")
		)
		(fp_line
			(start 0.12065 -0.2794)
			(end 0.12065 -0.3048)
			(stroke
				(width 0.1)
				(type default)
			)
			(layer "F.Fab")
		)
		(fp_line
			(start 0.67945 -0.3048)
			(end 0.67945 0.3048)
			(stroke
				(width 0.1)
				(type default)
			)
			(layer "F.Fab")
		)
		(fp_line
			(start 0.67945 0.3048)
			(end 0.120396 0.3048)
			(stroke
				(width 0.1)
				(type default)
			)
			(layer "F.Fab")
		)
		(pad "1" smd rect
			(at -0.40005 0 180)
			(size 0.4572 0.508)
			(layers "F.Cu" "F.Mask" "F.Paste")
			(net "FAN_4_PWM")
		)
		(pad "2" smd rect
			(at 0.40005 0 180)
			(size 0.4572 0.508)
			(layers "F.Cu" "F.Mask" "F.Paste")
			(net "FAN_4_PWM_R1")
		)
	)
)
